(kicad_pcb
	(version 20260206)
	(generator "pcbnew")
	(generator_version "10.0")
	(general
		(thickness 1.6)
		(legacy_teardrops no)
	)
	(paper "A4")
	(title_block
		(title "03242023_DA0F0TMBIJ0_F0T_Motherboard_J_brd_V01_OCP.brd")
		(comment 1 "Grand Teton / footprints 643-646 of 6105")
	)
	(layers
		(0 "F.Cu" signal "TOP")
		(4 "In1.Cu" signal "GND")
		(6 "In2.Cu" signal "IN1")
		(8 "In3.Cu" signal "GND1")
		(10 "In4.Cu" signal "IN2")
		(12 "In5.Cu" signal "GND2")
		(14 "In6.Cu" signal "IN3")
		(16 "In7.Cu" signal "GND3")
		(18 "In8.Cu" signal "VCC")
		(20 "In9.Cu" signal "VCC1")
		(22 "In10.Cu" signal "GND4")
		(24 "In11.Cu" signal "IN4")
		(26 "In12.Cu" signal "GND5")
		(28 "In13.Cu" signal "IN5")
		(30 "In14.Cu" signal "GND6")
		(32 "In15.Cu" signal "IN6")
		(34 "In16.Cu" signal "GND7")
		(2 "B.Cu" signal "BOTTOM")
		(9 "F.Adhes" user "F.Adhesive")
		(11 "B.Adhes" user "B.Adhesive")
		(13 "F.Paste" user "Package Geometry/Pastemask Top")
		(15 "B.Paste" user "Package Geometry/Pastemask Bottom")
		(5 "F.SilkS" user "Ref Des/Silkscreen Top")
		(7 "B.SilkS" user "Ref Des/Silkscreen Bottom")
		(1 "F.Mask" user "Board Geometry/Soldermask Top")
		(3 "B.Mask" user "Board Geometry/Soldermask Bottom")
		(17 "Dwgs.User" user "User.Drawings")
		(19 "Cmts.User" user "User.Comments")
		(21 "Eco1.User" user "User.Eco1")
		(23 "Eco2.User" user "User.Eco2")
		(25 "Edge.Cuts" user "Board Geometry/Outline")
		(27 "Margin" user)
		(31 "F.CrtYd" user "Package Geometry/Place Bound Top")
		(29 "B.CrtYd" user "Package Geometry/Place Bound Bottom")
		(35 "F.Fab" user "Ref Des/Assembly Top")
		(33 "B.Fab" user "Ref Des/Assembly Bottom")
	)
	(footprint ""
		(layer "F.Cu")
		(at 215.33739 -104.33304 180)
		(property "Reference" "U205"
			(at 6.09854 -2.351532 0)
			(unlocked yes)
			(layer "F.SilkS")
			(effects
				(font
					(size 0.7874 0.5842)
					(thickness 0.1524)
				)
				(justify left)
			)
		)
		(property "Value" ""
			(at 0 0 180)
			(layer "F.Fab")
			(effects
				(font
					(size 1.27 1.27)
				)
			)
		)
		(duplicate_pad_numbers_are_jumpers no)
		(fp_line
			(start 2.03581 1.525016)
			(end 2.03581 -1.525016)
			(stroke
				(width 0.1524)
				(type default)
			)
			(layer "F.SilkS")
		)
		(fp_line
			(start 2.03581 -1.525016)
			(end 0.82423 -1.525016)
			(stroke
				(width 0.1524)
				(type default)
			)
			(layer "F.SilkS")
		)
		(fp_line
			(start 0.82423 -1.525016)
			(end 0 -0.649986)
			(stroke
				(width 0.1524)
				(type default)
			)
			(layer "F.SilkS")
		)
		(fp_line
			(start 0 -0.649986)
			(end -0.82423 -1.525016)
			(stroke
				(width 0.1524)
				(type default)
			)
			(layer "F.SilkS")
		)
		(fp_line
			(start -0.82423 -1.525016)
			(end -2.03581 -1.525016)
			(stroke
				(width 0.1524)
				(type default)
			)
			(layer "F.SilkS")
		)
		(fp_line
			(start -2.03581 1.525016)
			(end 2.03581 1.525016)
			(stroke
				(width 0.1524)
				(type default)
			)
			(layer "F.SilkS")
		)
		(fp_line
			(start -2.03581 -1.525016)
			(end -2.03581 1.525016)
			(stroke
				(width 0.1524)
				(type default)
			)
			(layer "F.SilkS")
		)
		(fp_poly
			(pts
				(xy -2.335276 -1.224788) (xy -3.151378 -1.497076) (xy -2.60731 -2.041144)
			)
			(stroke
				(width 0)
				(type default)
			)
			(fill yes)
			(layer "F.SilkS")
		)
		(fp_line
			(start 0.87503 1.525016)
			(end 0.87503 -1.525016)
			(stroke
				(width 0.1)
				(type default)
			)
			(layer "F.Fab")
		)
		(fp_line
			(start 0.87503 -1.525016)
			(end -0.87503 -1.525016)
			(stroke
				(width 0.1)
				(type default)
			)
			(layer "F.Fab")
		)
		(fp_line
			(start -0.87503 1.525016)
			(end 0.87503 1.525016)
			(stroke
				(width 0.1)
				(type default)
			)
			(layer "F.Fab")
		)
		(fp_line
			(start -0.87503 -1.525016)
			(end -0.87503 1.525016)
			(stroke
				(width 0.1)
				(type default)
			)
			(layer "F.Fab")
		)
		(fp_poly
			(pts
				(xy -2.12979 -0.943356) (xy -2.89941 -0.5588) (xy -2.89941 -1.328166)
			)
			(stroke
				(width 0)
				(type default)
			)
			(fill yes)
			(layer "F.Fab")
		)
		(pad "1" smd rect
			(at -1.35001 -0.94996 90)
			(size 0.6096 1.1176)
			(layers "F.Cu" "F.Mask" "F.Paste")
			(net "PWRGD_DSW_PWROK_R4")
		)
		(pad "2" smd rect
			(at -1.35001 0 90)
			(size 0.6096 1.1176)
			(layers "F.Cu" "F.Mask" "F.Paste")
			(net "GND")
		)
		(pad "3" smd rect
			(at -1.35001 0.94996 90)
			(size 0.6096 1.1176)
			(layers "F.Cu" "F.Mask" "F.Paste")
			(net "A_HSC_INAP")
		)
		(pad "4" smd rect
			(at 1.35001 0.94996 90)
			(size 0.6096 1.1176)
			(layers "F.Cu" "F.Mask" "F.Paste")
			(net "NC_U205_INB-")
		)
		(pad "5" smd rect
			(at 1.35001 0 90)
			(size 0.6096 1.1176)
			(layers "F.Cu" "F.Mask" "F.Paste")
			(net "U205_VDD")
		)
		(pad "6" smd rect
			(at 1.35001 -0.94996 90)
			(size 0.6096 1.1176)
			(layers "F.Cu" "F.Mask" "F.Paste")
			(net "NC_U205_OUTB")
		)
	)
	(footprint ""
		(layer "F.Cu")
		(at 49.3903 -389.985758 180)
		(property "Reference" "R4645"
			(at 0 0 180)
			(layer "F.SilkS")
			(hide yes)
			(effects
				(font
					(size 1.27 1.27)
				)
			)
		)
		(property "Value" ""
			(at 0 0 180)
			(layer "F.Fab")
			(effects
				(font
					(size 1.27 1.27)
				)
			)
		)
		(duplicate_pad_numbers_are_jumpers no)
		(fp_line
			(start 0.7874 0.4064)
			(end -0.7874 0.4064)
			(stroke
				(width 0.1524)
				(type default)
			)
			(layer "F.SilkS")
		)
		(fp_line
			(start 0.7874 -0.4064)
			(end 0.7874 0.4064)
			(stroke
				(width 0.1524)
				(type default)
			)
			(layer "F.SilkS")
		)
		(fp_line
			(start -0.7874 0.4064)
			(end -0.7874 -0.4064)
			(stroke
				(width 0.1524)
				(type default)
			)
			(layer "F.SilkS")
		)
		(fp_line
			(start -0.7874 -0.4064)
			(end 0.7874 -0.4064)
			(stroke
				(width 0.1524)
				(type default)
			)
			(layer "F.SilkS")
		)
		(fp_line
			(start 0.67945 0.3048)
			(end 0.120396 0.3048)
			(stroke
				(width 0.1)
				(type default)
			)
			(layer "F.Fab")
		)
		(fp_line
			(start 0.67945 -0.3048)
			(end 0.67945 0.3048)
			(stroke
				(width 0.1)
				(type default)
			)
			(layer "F.Fab")
		)
		(fp_line
			(start 0.12065 -0.2794)
			(end 0.12065 -0.3048)
			(stroke
				(width 0.1)
				(type default)
			)
			(layer "F.Fab")
		)
		(fp_line
			(start 0.12065 -0.3048)
			(end 0.67945 -0.3048)
			(stroke
				(width 0.1)
				(type default)
			)
			(layer "F.Fab")
		)
		(fp_line
			(start 0.120396 0.3048)
			(end 0.120396 0.2794)
			(stroke
				(width 0.1)
				(type default)
			)
			(layer "F.Fab")
		)
		(fp_line
			(start 0.120396 0.2794)
			(end -0.12065 0.2794)
			(stroke
				(width 0.1)
				(type default)
			)
			(layer "F.Fab")
		)
		(fp_line
			(start -0.12065 0.3048)
			(end -0.67945 0.3048)
			(stroke
				(width 0.1)
				(type default)
			)
			(layer "F.Fab")
		)
		(fp_line
			(start -0.12065 0.2794)
			(end -0.12065 0.3048)
			(stroke
				(width 0.1)
				(type default)
			)
			(layer "F.Fab")
		)
		(fp_line
			(start -0.12065 -0.2794)
			(end 0.12065 -0.2794)
			(stroke
				(width 0.1)
				(type default)
			)
			(layer "F.Fab")
		)
		(fp_line
			(start -0.12065 -0.305054)
			(end -0.12065 -0.2794)
			(stroke
				(width 0.1)
				(type default)
			)
			(layer "F.Fab")
		)
		(fp_line
			(start -0.67945 0.3048)
			(end -0.67945 -0.305054)
			(stroke
				(width 0.1)
				(type default)
			)
			(layer "F.Fab")
		)
		(fp_line
			(start -0.67945 -0.305054)
			(end -0.12065 -0.305054)
			(stroke
				(width 0.1)
				(type default)
			)
			(layer "F.Fab")
		)
		(pad "1" smd circle
			(at -0.40005 0 180)
			(size 0 0)
			(layers "F.Cu" "F.Mask" "F.Paste")
			(net "P3V3_AUX")
		)
		(pad "2" smd circle
			(at 0.40005 0 180)
			(size 0 0)
			(layers "F.Cu" "F.Mask" "F.Paste")
			(net "FM_P2E_BUF2_EQB0")
		)
	)
	(footprint ""
		(layer "F.Cu")
		(at 24.892 -419.5572 180)
		(property "Reference" "R4736"
			(at 0 0 180)
			(layer "F.SilkS")
			(hide yes)
			(effects
				(font
					(size 1.27 1.27)
				)
			)
		)
		(property "Value" ""
			(at 0 0 180)
			(layer "F.Fab")
			(effects
				(font
					(size 1.27 1.27)
				)
			)
		)
		(duplicate_pad_numbers_are_jumpers no)
		(fp_line
			(start 0.7874 0.4064)
			(end -0.7874 0.4064)
			(stroke
				(width 0.1524)
				(type default)
			)
			(layer "F.SilkS")
		)
		(fp_line
			(start 0.7874 -0.4064)
			(end 0.7874 0.4064)
			(stroke
				(width 0.1524)
				(type default)
			)
			(layer "F.SilkS")
		)
		(fp_line
			(start -0.7874 0.4064)
			(end -0.7874 -0.4064)
			(stroke
				(width 0.1524)
				(type default)
			)
			(layer "F.SilkS")
		)
		(fp_line
			(start -0.7874 -0.4064)
			(end 0.7874 -0.4064)
			(stroke
				(width 0.1524)
				(type default)
			)
			(layer "F.SilkS")
		)
		(fp_line
			(start 0.67945 0.3048)
			(end 0.120396 0.3048)
			(stroke
				(width 0.1)
				(type default)
			)
			(layer "F.Fab")
		)
		(fp_line
			(start 0.67945 -0.3048)
			(end 0.67945 0.3048)
			(stroke
				(width 0.1)
				(type default)
			)
			(layer "F.Fab")
		)
		(fp_line
			(start 0.12065 -0.2794)
			(end 0.12065 -0.3048)
			(stroke
				(width 0.1)
				(type default)
			)
			(layer "F.Fab")
		)
		(fp_line
			(start 0.12065 -0.3048)
			(end 0.67945 -0.3048)
			(stroke
				(width 0.1)
				(type default)
			)
			(layer "F.Fab")
		)
		(fp_line
			(start 0.120396 0.3048)
			(end 0.120396 0.2794)
			(stroke
				(width 0.1)
				(type default)
			)
			(layer "F.Fab")
		)
		(fp_line
			(start 0.120396 0.2794)
			(end -0.12065 0.2794)
			(stroke
				(width 0.1)
				(type default)
			)
			(layer "F.Fab")
		)
		(fp_line
			(start -0.12065 0.3048)
			(end -0.67945 0.3048)
			(stroke
				(width 0.1)
				(type default)
			)
			(layer "F.Fab")
		)
		(fp_line
			(start -0.12065 0.2794)
			(end -0.12065 0.3048)
			(stroke
				(width 0.1)
				(type default)
			)
			(layer "F.Fab")
		)
		(fp_line
			(start -0.12065 -0.2794)
			(end 0.12065 -0.2794)
			(stroke
				(width 0.1)
				(type default)
			)
			(layer "F.Fab")
		)
		(fp_line
			(start -0.12065 -0.305054)
			(end -0.12065 -0.2794)
			(stroke
				(width 0.1)
				(type default)
			)
			(layer "F.Fab")
		)
		(fp_line
			(start -0.67945 0.3048)
			(end -0.67945 -0.305054)
			(stroke
				(width 0.1)
				(type default)
			)
			(layer "F.Fab")
		)
		(fp_line
			(start -0.67945 -0.305054)
			(end -0.12065 -0.305054)
			(stroke
				(width 0.1)
				(type default)
			)
			(layer "F.Fab")
		)
		(pad "1" smd circle
			(at -0.40005 0 180)
			(size 0 0)
			(layers "F.Cu" "F.Mask" "F.Paste")
			(net "PRSNT_CABLE_GPU_A2_ISO_N")
		)
		(pad "2" smd circle
			(at 0.40005 0 180)
			(size 0 0)
			(layers "F.Cu" "F.Mask" "F.Paste")
			(net "PRSNT_CABLE_GPU_A2_ISO_R1_N")
		)
	)
	(footprint ""
		(layer "F.Cu")
		(at 217.583766 -16.381222 -90)
		(property "Reference" "R3181"
			(at 0 0 270)
			(layer "F.SilkS")
			(hide yes)
			(effects
				(font
					(size 1.27 1.27)
				)
			)
		)
		(property "Value" ""
			(at 0 0 270)
			(layer "F.Fab")
			(effects
				(font
					(size 1.27 1.27)
				)
			)
		)
		(duplicate_pad_numbers_are_jumpers no)
		(fp_line
			(start -0.7874 0.4064)
			(end -0.7874 -0.4064)
			(stroke
				(width 0.1524)
				(type default)
			)
			(layer "F.SilkS")
		)
		(fp_line
			(start 0.7874 0.4064)
			(end -0.7874 0.4064)
			(stroke
				(width 0.1524)
				(type default)
			)
			(layer "F.SilkS")
		)
		(fp_line
			(start -0.7874 -0.4064)
			(end 0.7874 -0.4064)
			(stroke
				(width 0.1524)
				(type default)
			)
			(layer "F.SilkS")
		)
		(fp_line
			(start 0.7874 -0.4064)
			(end 0.7874 0.4064)
			(stroke
				(width 0.1524)
				(type default)
			)
			(layer "F.SilkS")
		)
		(fp_line
			(start -0.67945 0.3048)
			(end -0.67945 -0.305054)
			(stroke
				(width 0.1)
				(type default)
			)
			(layer "F.Fab")
		)
		(fp_line
			(start -0.12065 0.3048)
			(end -0.67945 0.3048)
			(stroke
				(width 0.1)
				(type default)
			)
			(layer "F.Fab")
		)
		(fp_line
			(start 0.120396 0.3048)
			(end 0.120396 0.2794)
			(stroke
				(width 0.1)
				(type default)
			)
			(layer "F.Fab")
		)
		(fp_line
			(start 0.67945 0.3048)
			(end 0.120396 0.3048)
			(stroke
				(width 0.1)
				(type default)
			)
			(layer "F.Fab")
		)
		(fp_line
			(start -0.12065 0.2794)
			(end -0.12065 0.3048)
			(stroke
				(width 0.1)
				(type default)
			)
			(layer "F.Fab")
		)
		(fp_line
			(start 0.120396 0.2794)
			(end -0.12065 0.2794)
			(stroke
				(width 0.1)
				(type default)
			)
			(layer "F.Fab")
		)
		(fp_line
			(start -0.12065 -0.2794)
			(end 0.12065 -0.2794)
			(stroke
				(width 0.1)
				(type default)
			)
			(layer "F.Fab")
		)
		(fp_line
			(start 0.12065 -0.2794)
			(end 0.12065 -0.3048)
			(stroke
				(width 0.1)
				(type default)
			)
			(layer "F.Fab")
		)
		(fp_line
			(start 0.12065 -0.3048)
			(end 0.67945 -0.3048)
			(stroke
				(width 0.1)
				(type default)
			)
			(layer "F.Fab")
		)
		(fp_line
			(start 0.67945 -0.3048)
			(end 0.67945 0.3048)
			(stroke
				(width 0.1)
				(type default)
			)
			(layer "F.Fab")
		)
		(fp_line
			(start -0.67945 -0.305054)
			(end -0.12065 -0.305054)
			(stroke
				(width 0.1)
				(type default)
			)
			(layer "F.Fab")
		)
		(fp_line
			(start -0.12065 -0.305054)
			(end -0.12065 -0.2794)
			(stroke
				(width 0.1)
				(type default)
			)
			(layer "F.Fab")
		)
		(pad "1" smd circle
			(at -0.40005 0 270)
			(size 0 0)
			(layers "F.Cu" "F.Mask" "F.Paste")
			(net "CLK_50M_NCSI_OCP_2")
		)
		(pad "2" smd circle
			(at 0.40005 0 270)
			(size 0 0)
			(layers "F.Cu" "F.Mask" "F.Paste")
			(net "CLK_50M_NCSI_OCP_V3_2")
		)
	)
)
